# T6G (Grand Teton) — schematic netlist excerpt (pin names and nets, part order shuffled) for the footprints in the layout excerpt that follows; sources: Cadence DE-HDL packaged netlist, KiCad conversion of 04192023_DAF0TMB3IC0_F0TG_MB_C_brd_V02_OCP.brd

R1524  Q_RES  0 5% CHIP  pkg 0402LF  page 142 : A = HP_LVC3_OCP_V3_2_PWRGD_R2 ; B = OCP_V3_2_P3V3_R3_PWRGD
R3297  Q_RES  10K 1% CHIP  pkg 0402LF  page 144 : A = LED_HDD_ACTIVITY_B_N ; B = GND

(kicad_pcb
	(version 20260206)
	(generator "pcbnew")
	(generator_version "10.0")
	(general
		(thickness 1.6)
		(legacy_teardrops no)
	)
	(paper "A4")
	(title_block
		(title "04192023_DAF0TMB3IC0_F0TG_MB_C_brd_V02_OCP.brd")
		(comment 1 "Grand Teton / footprints 4695-4696 of 8354")
	)
	(layers
		(0 "F.Cu" signal "TOP")
		(4 "In1.Cu" signal "GND")
		(6 "In2.Cu" signal "IN1")
		(8 "In3.Cu" signal "GND1")
		(10 "In4.Cu" signal "IN2")
		(12 "In5.Cu" signal "GND2")
		(14 "In6.Cu" signal "IN3")
		(16 "In7.Cu" signal "GND3")
		(18 "In8.Cu" signal "VCC")
		(20 "In9.Cu" signal "VCC1")
		(22 "In10.Cu" signal "GND4")
		(24 "In11.Cu" signal "IN4")
		(26 "In12.Cu" signal "GND5")
		(28 "In13.Cu" signal "IN5")
		(30 "In14.Cu" signal "GND6")
		(32 "In15.Cu" signal "IN6")
		(34 "In16.Cu" signal "GND7")
		(2 "B.Cu" signal "BOTTOM")
		(9 "F.Adhes" user "F.Adhesive")
		(11 "B.Adhes" user "B.Adhesive")
		(13 "F.Paste" user "Package Geometry/Pastemask Top")
		(15 "B.Paste" user "Package Geometry/Pastemask Bottom")
		(5 "F.SilkS" user "Ref Des/Silkscreen Top")
		(7 "B.SilkS" user "Ref Des/Silkscreen Bottom")
		(1 "F.Mask" user "Board Geometry/Soldermask Top")
		(3 "B.Mask" user "Board Geometry/Soldermask Bottom")
		(17 "Dwgs.User" user "User.Drawings")
		(19 "Cmts.User" user "User.Comments")
		(21 "Eco1.User" user "User.Eco1")
		(23 "Eco2.User" user "User.Eco2")
		(25 "Edge.Cuts" user "Board Geometry/Outline")
		(27 "Margin" user)
		(31 "F.CrtYd" user "Package Geometry/Place Bound Top")
		(29 "B.CrtYd" user "Package Geometry/Place Bound Bottom")
		(35 "F.Fab" user "Ref Des/Assembly Top")
		(33 "B.Fab" user "Ref Des/Assembly Bottom")
	)
	(footprint ""
		(layer "F.Cu")
		(at 66.47434 -52.74564)
		(property "Reference" "R1524"
			(at 0 0 0)
			(layer "F.SilkS")
			(hide yes)
			(effects
				(font
					(size 1.27 1.27)
				)
			)
		)
		(property "Value" ""
			(at 0 0 0)
			(layer "F.Fab")
			(effects
				(font
					(size 1.27 1.27)
				)
			)
		)
		(duplicate_pad_numbers_are_jumpers no)
		(fp_line
			(start -0.7874 -0.4064)
			(end 0.7874 -0.4064)
			(stroke
				(width 0.1524)
				(type default)
			)
			(layer "F.SilkS")
		)
		(fp_line
			(start -0.7874 0.4064)
			(end -0.7874 -0.4064)
			(stroke
				(width 0.1524)
				(type default)
			)
			(layer "F.SilkS")
		)
		(fp_line
			(start 0.7874 -0.4064)
			(end 0.7874 0.4064)
			(stroke
				(width 0.1524)
				(type default)
			)
			(layer "F.SilkS")
		)
		(fp_line
			(start 0.7874 0.4064)
			(end -0.7874 0.4064)
			(stroke
				(width 0.1524)
				(type default)
			)
			(layer "F.SilkS")
		)
		(fp_line
			(start -0.67945 -0.305054)
			(end -0.12065 -0.305054)
			(stroke
				(width 0.1)
				(type default)
			)
			(layer "F.Fab")
		)
		(fp_line
			(start -0.67945 0.3048)
			(end -0.67945 -0.305054)
			(stroke
				(width 0.1)
				(type default)
			)
			(layer "F.Fab")
		)
		(fp_line
			(start -0.12065 -0.305054)
			(end -0.12065 -0.2794)
			(stroke
				(width 0.1)
				(type default)
			)
			(layer "F.Fab")
		)
		(fp_line
			(start -0.12065 -0.2794)
			(end 0.12065 -0.2794)
			(stroke
				(width 0.1)
				(type default)
			)
			(layer "F.Fab")
		)
		(fp_line
			(start -0.12065 0.2794)
			(end -0.12065 0.3048)
			(stroke
				(width 0.1)
				(type default)
			)
			(layer "F.Fab")
		)
		(fp_line
			(start -0.12065 0.3048)
			(end -0.67945 0.3048)
			(stroke
				(width 0.1)
				(type default)
			)
			(layer "F.Fab")
		)
		(fp_line
			(start 0.120396 0.2794)
			(end -0.12065 0.2794)
			(stroke
				(width 0.1)
				(type default)
			)
			(layer "F.Fab")
		)
		(fp_line
			(start 0.120396 0.3048)
			(end 0.120396 0.2794)
			(stroke
				(width 0.1)
				(type default)
			)
			(layer "F.Fab")
		)
		(fp_line
			(start 0.12065 -0.3048)
			(end 0.67945 -0.3048)
			(stroke
				(width 0.1)
				(type default)
			)
			(layer "F.Fab")
		)
		(fp_line
			(start 0.12065 -0.2794)
			(end 0.12065 -0.3048)
			(stroke
				(width 0.1)
				(type default)
			)
			(layer "F.Fab")
		)
		(fp_line
			(start 0.67945 -0.3048)
			(end 0.67945 0.3048)
			(stroke
				(width 0.1)
				(type default)
			)
			(layer "F.Fab")
		)
		(fp_line
			(start 0.67945 0.3048)
			(end 0.120396 0.3048)
			(stroke
				(width 0.1)
				(type default)
			)
			(layer "F.Fab")
		)
		(pad "1" smd circle
			(at -0.40005 0)
			(size 0 0)
			(layers "F.Cu" "F.Mask" "F.Paste")
			(net "HP_LVC3_OCP_V3_2_PWRGD_R2")
		)
		(pad "2" smd circle
			(at 0.40005 0)
			(size 0 0)
			(layers "F.Cu" "F.Mask" "F.Paste")
			(net "OCP_V3_2_P3V3_R3_PWRGD")
		)
	)
	(footprint ""
		(layer "F.Cu")
		(at 156.30779 -101.638862 -90)
		(property "Reference" "R3297"
			(at 0 0 270)
			(layer "F.SilkS")
			(hide yes)
			(effects
				(font
					(size 1.27 1.27)
				)
			)
		)
		(property "Value" ""
			(at 0 0 270)
			(layer "F.Fab")
			(effects
				(font
					(size 1.27 1.27)
				)
			)
		)
		(duplicate_pad_numbers_are_jumpers no)
		(fp_line
			(start -0.7874 0.4064)
			(end -0.7874 -0.4064)
			(stroke
				(width 0.1524)
				(type default)
			)
			(layer "F.SilkS")
		)
		(fp_line
			(start 0.7874 0.4064)
			(end -0.7874 0.4064)
			(stroke
				(width 0.1524)
				(type default)
			)
			(layer "F.SilkS")
		)
		(fp_line
			(start -0.7874 -0.4064)
			(end 0.7874 -0.4064)
			(stroke
				(width 0.1524)
				(type default)
			)
			(layer "F.SilkS")
		)
		(fp_line
			(start 0.7874 -0.4064)
			(end 0.7874 0.4064)
			(stroke
				(width 0.1524)
				(type default)
			)
			(layer "F.SilkS")
		)
		(fp_line
			(start -0.67945 0.3048)
			(end -0.67945 -0.305054)
			(stroke
				(width 0.1)
				(type default)
			)
			(layer "F.Fab")
		)
		(fp_line
			(start -0.12065 0.3048)
			(end -0.67945 0.3048)
			(stroke
				(width 0.1)
				(type default)
			)
			(layer "F.Fab")
		)
		(fp_line
			(start 0.120396 0.3048)
			(end 0.120396 0.2794)
			(stroke
				(width 0.1)
				(type default)
			)
			(layer "F.Fab")
		)
		(fp_line
			(start 0.67945 0.3048)
			(end 0.120396 0.3048)
			(stroke
				(width 0.1)
				(type default)
			)
			(layer "F.Fab")
		)
		(fp_line
			(start -0.12065 0.2794)
			(end -0.12065 0.3048)
			(stroke
				(width 0.1)
				(type default)
			)
			(layer "F.Fab")
		)
		(fp_line
			(start 0.120396 0.2794)
			(end -0.12065 0.2794)
			(stroke
				(width 0.1)
				(type default)
			)
			(layer "F.Fab")
		)
		(fp_line
			(start -0.12065 -0.2794)
			(end 0.12065 -0.2794)
			(stroke
				(width 0.1)
				(type default)
			)
			(layer "F.Fab")
		)
		(fp_line
			(start 0.12065 -0.2794)
			(end 0.12065 -0.3048)
			(stroke
				(width 0.1)
				(type default)
			)
			(layer "F.Fab")
		)
		(fp_line
			(start 0.12065 -0.3048)
			(end 0.67945 -0.3048)
			(stroke
				(width 0.1)
				(type default)
			)
			(layer "F.Fab")
		)
		(fp_line
			(start 0.67945 -0.3048)
			(end 0.67945 0.3048)
			(stroke
				(width 0.1)
				(type default)
			)
			(layer "F.Fab")
		)
		(fp_line
			(start -0.67945 -0.305054)
			(end -0.12065 -0.305054)
			(stroke
				(width 0.1)
				(type default)
			)
			(layer "F.Fab")
		)
		(fp_line
			(start -0.12065 -0.305054)
			(end -0.12065 -0.2794)
			(stroke
				(width 0.1)
				(type default)
			)
			(layer "F.Fab")
		)
		(pad "1" smd circle
			(at -0.40005 0 270)
			(size 0 0)
			(layers "F.Cu" "F.Mask" "F.Paste")
			(net "LED_HDD_ACTIVITY_B_N")
		)
		(pad "2" smd circle
			(at 0.40005 0 270)
			(size 0 0)
			(layers "F.Cu" "F.Mask" "F.Paste")
			(net "GND")
		)
	)
)
